# S9S_MB_2U (Grand Teton) — schematic netlist excerpt (pin names and nets, part order shuffled) for the footprints in the layout excerpt that follows; sources: Cadence DE-HDL packaged netlist, KiCad conversion of 03242023_DA0F0TMBIJ0_F0T_Motherboard_J_brd_V01_OCP.brd

R126  Q_RES  0 5% CHIP  pkg 0402LF  page 125 : A = PWRGD_DRAMPWRGD_CPU1_EF_R_LVC1 ; B = PWRGD_DRAMPWRGD_CPU1_EF_LVC1_R2
R3208  Q_RES  100 1% CHIP  pkg 0402LF  page 160 : A = OCP_V3_2_ISO_BIF0_EN ; B = GND

(kicad_pcb
	(version 20260206)
	(generator "pcbnew")
	(generator_version "10.0")
	(general
		(thickness 1.6)
		(legacy_teardrops no)
	)
	(paper "A4")
	(title_block
		(title "03242023_DA0F0TMBIJ0_F0T_Motherboard_J_brd_V01_OCP.brd")
		(comment 1 "Grand Teton / footprints 5240-5241 of 6105")
	)
	(layers
		(0 "F.Cu" signal "TOP")
		(4 "In1.Cu" signal "GND")
		(6 "In2.Cu" signal "IN1")
		(8 "In3.Cu" signal "GND1")
		(10 "In4.Cu" signal "IN2")
		(12 "In5.Cu" signal "GND2")
		(14 "In6.Cu" signal "IN3")
		(16 "In7.Cu" signal "GND3")
		(18 "In8.Cu" signal "VCC")
		(20 "In9.Cu" signal "VCC1")
		(22 "In10.Cu" signal "GND4")
		(24 "In11.Cu" signal "IN4")
		(26 "In12.Cu" signal "GND5")
		(28 "In13.Cu" signal "IN5")
		(30 "In14.Cu" signal "GND6")
		(32 "In15.Cu" signal "IN6")
		(34 "In16.Cu" signal "GND7")
		(2 "B.Cu" signal "BOTTOM")
		(9 "F.Adhes" user "F.Adhesive")
		(11 "B.Adhes" user "B.Adhesive")
		(13 "F.Paste" user "Package Geometry/Pastemask Top")
		(15 "B.Paste" user "Package Geometry/Pastemask Bottom")
		(5 "F.SilkS" user "Ref Des/Silkscreen Top")
		(7 "B.SilkS" user "Ref Des/Silkscreen Bottom")
		(1 "F.Mask" user "Board Geometry/Soldermask Top")
		(3 "B.Mask" user "Board Geometry/Soldermask Bottom")
		(17 "Dwgs.User" user "User.Drawings")
		(19 "Cmts.User" user "User.Comments")
		(21 "Eco1.User" user "User.Eco1")
		(23 "Eco2.User" user "User.Eco2")
		(25 "Edge.Cuts" user "Board Geometry/Outline")
		(27 "Margin" user)
		(31 "F.CrtYd" user "Package Geometry/Place Bound Top")
		(29 "B.CrtYd" user "Package Geometry/Place Bound Bottom")
		(35 "F.Fab" user "Ref Des/Assembly Top")
		(33 "B.Fab" user "Ref Des/Assembly Bottom")
	)
	(footprint ""
		(layer "B.Cu")
		(at 200.661778 -109.86897 180)
		(property "Reference" "R126"
			(at 0 0 0)
			(layer "B.SilkS")
			(hide yes)
			(effects
				(font
					(size 1.27 1.27)
				)
				(justify mirror)
			)
		)
		(property "Value" ""
			(at 0 0 0)
			(layer "B.Fab")
			(effects
				(font
					(size 1.27 1.27)
				)
				(justify mirror)
			)
		)
		(duplicate_pad_numbers_are_jumpers no)
		(fp_line
			(start 0.7874 0.4064)
			(end 0.7874 -0.4064)
			(stroke
				(width 0.1524)
				(type default)
			)
			(layer "B.SilkS")
		)
		(fp_line
			(start 0.7874 -0.4064)
			(end -0.7874 -0.4064)
			(stroke
				(width 0.1524)
				(type default)
			)
			(layer "B.SilkS")
		)
		(fp_line
			(start -0.7874 0.4064)
			(end 0.7874 0.4064)
			(stroke
				(width 0.1524)
				(type default)
			)
			(layer "B.SilkS")
		)
		(fp_line
			(start -0.7874 -0.4064)
			(end -0.7874 0.4064)
			(stroke
				(width 0.1524)
				(type default)
			)
			(layer "B.SilkS")
		)
		(fp_line
			(start 0.67945 0.3048)
			(end 0.67945 -0.305054)
			(stroke
				(width 0.1)
				(type default)
			)
			(layer "B.Fab")
		)
		(fp_line
			(start 0.67945 -0.305054)
			(end 0.12065 -0.305054)
			(stroke
				(width 0.1)
				(type default)
			)
			(layer "B.Fab")
		)
		(fp_line
			(start 0.12065 0.3048)
			(end 0.67945 0.3048)
			(stroke
				(width 0.1)
				(type default)
			)
			(layer "B.Fab")
		)
		(fp_line
			(start 0.12065 0.2794)
			(end 0.12065 0.3048)
			(stroke
				(width 0.1)
				(type default)
			)
			(layer "B.Fab")
		)
		(fp_line
			(start 0.12065 -0.2794)
			(end -0.12065 -0.2794)
			(stroke
				(width 0.1)
				(type default)
			)
			(layer "B.Fab")
		)
		(fp_line
			(start 0.12065 -0.305054)
			(end 0.12065 -0.2794)
			(stroke
				(width 0.1)
				(type default)
			)
			(layer "B.Fab")
		)
		(fp_line
			(start -0.120396 0.3048)
			(end -0.120396 0.2794)
			(stroke
				(width 0.1)
				(type default)
			)
			(layer "B.Fab")
		)
		(fp_line
			(start -0.120396 0.2794)
			(end 0.12065 0.2794)
			(stroke
				(width 0.1)
				(type default)
			)
			(layer "B.Fab")
		)
		(fp_line
			(start -0.12065 -0.2794)
			(end -0.12065 -0.3048)
			(stroke
				(width 0.1)
				(type default)
			)
			(layer "B.Fab")
		)
		(fp_line
			(start -0.12065 -0.3048)
			(end -0.67945 -0.3048)
			(stroke
				(width 0.1)
				(type default)
			)
			(layer "B.Fab")
		)
		(fp_line
			(start -0.67945 0.3048)
			(end -0.120396 0.3048)
			(stroke
				(width 0.1)
				(type default)
			)
			(layer "B.Fab")
		)
		(fp_line
			(start -0.67945 -0.3048)
			(end -0.67945 0.3048)
			(stroke
				(width 0.1)
				(type default)
			)
			(layer "B.Fab")
		)
		(pad "1" smd circle
			(at 0.40005 0)
			(size 0 0)
			(layers "B.Cu" "B.Mask" "B.Paste")
			(net "PWRGD_DRAMPWRGD_CPU1_EF_R_LVC1")
		)
		(pad "2" smd circle
			(at -0.40005 0)
			(size 0 0)
			(layers "B.Cu" "B.Mask" "B.Paste")
			(net "PWRGD_DRAMPWRGD_CPU1_EF_LVC1_R2")
		)
	)
	(footprint ""
		(layer "B.Cu")
		(at 63.718186 -15.772384 90)
		(property "Reference" "R3208"
			(at 0 0 90)
			(layer "B.SilkS")
			(hide yes)
			(effects
				(font
					(size 1.27 1.27)
				)
				(justify mirror)
			)
		)
		(property "Value" ""
			(at 0 0 90)
			(layer "B.Fab")
			(effects
				(font
					(size 1.27 1.27)
				)
				(justify mirror)
			)
		)
		(duplicate_pad_numbers_are_jumpers no)
		(fp_line
			(start 0.7874 -0.4064)
			(end -0.7874 -0.4064)
			(stroke
				(width 0.1524)
				(type default)
			)
			(layer "B.SilkS")
		)
		(fp_line
			(start -0.7874 -0.4064)
			(end -0.7874 0.4064)
			(stroke
				(width 0.1524)
				(type default)
			)
			(layer "B.SilkS")
		)
		(fp_line
			(start 0.7874 0.4064)
			(end 0.7874 -0.4064)
			(stroke
				(width 0.1524)
				(type default)
			)
			(layer "B.SilkS")
		)
		(fp_line
			(start -0.7874 0.4064)
			(end 0.7874 0.4064)
			(stroke
				(width 0.1524)
				(type default)
			)
			(layer "B.SilkS")
		)
		(fp_line
			(start 0.67945 -0.305054)
			(end 0.12065 -0.305054)
			(stroke
				(width 0.1)
				(type default)
			)
			(layer "B.Fab")
		)
		(fp_line
			(start 0.12065 -0.305054)
			(end 0.12065 -0.2794)
			(stroke
				(width 0.1)
				(type default)
			)
			(layer "B.Fab")
		)
		(fp_line
			(start -0.12065 -0.3048)
			(end -0.67945 -0.3048)
			(stroke
				(width 0.1)
				(type default)
			)
			(layer "B.Fab")
		)
		(fp_line
			(start -0.67945 -0.3048)
			(end -0.67945 0.3048)
			(stroke
				(width 0.1)
				(type default)
			)
			(layer "B.Fab")
		)
		(fp_line
			(start 0.12065 -0.2794)
			(end -0.12065 -0.2794)
			(stroke
				(width 0.1)
				(type default)
			)
			(layer "B.Fab")
		)
		(fp_line
			(start -0.12065 -0.2794)
			(end -0.12065 -0.3048)
			(stroke
				(width 0.1)
				(type default)
			)
			(layer "B.Fab")
		)
		(fp_line
			(start 0.12065 0.2794)
			(end 0.12065 0.3048)
			(stroke
				(width 0.1)
				(type default)
			)
			(layer "B.Fab")
		)
		(fp_line
			(start -0.120396 0.2794)
			(end 0.12065 0.2794)
			(stroke
				(width 0.1)
				(type default)
			)
			(layer "B.Fab")
		)
		(fp_line
			(start 0.67945 0.3048)
			(end 0.67945 -0.305054)
			(stroke
				(width 0.1)
				(type default)
			)
			(layer "B.Fab")
		)
		(fp_line
			(start 0.12065 0.3048)
			(end 0.67945 0.3048)
			(stroke
				(width 0.1)
				(type default)
			)
			(layer "B.Fab")
		)
		(fp_line
			(start -0.120396 0.3048)
			(end -0.120396 0.2794)
			(stroke
				(width 0.1)
				(type default)
			)
			(layer "B.Fab")
		)
		(fp_line
			(start -0.67945 0.3048)
			(end -0.120396 0.3048)
			(stroke
				(width 0.1)
				(type default)
			)
			(layer "B.Fab")
		)
		(pad "1" smd circle
			(at 0.40005 0 270)
			(size 0 0)
			(layers "B.Cu" "B.Mask" "B.Paste")
			(net "OCP_V3_2_ISO_BIF0_EN")
		)
		(pad "2" smd circle
			(at -0.40005 0 270)
			(size 0 0)
			(layers "B.Cu" "B.Mask" "B.Paste")
			(net "GND")
		)
	)
)
